# TIMECARD (Time Appliance Project (Time Card)) — schematic netlist excerpt (pin names and nets, part order shuffled) for the footprints in the layout excerpt that follows; sources: Cadence DE-HDL packaged netlist, KiCad conversion of R4006-B0001-02_R01.brd

TP40  TP_PIONT  pkg TP010CT020B030_PTH  page 25 : \1\ = XP1R2V_FPGA_PG
R266  RESISTOR  33OHM 1%  pkg SMC_0402R_H016  page 21 : \1\ = RSVD_DBG_USB_MUX_SEL ; \2\ = XP5R0V_USB_CONN_DET
SP67  NULL  pkg DUMMY  page 34
R182  RESISTOR  0OHM -  pkg SMC_0402R_H016  page 30 : \1\ = XP1R8V_PG_R ; \2\ = XP1R8V_FPGA_PG

(kicad_pcb
	(version 20260206)
	(generator "pcbnew")
	(generator_version "10.0")
	(general
		(thickness 1.6)
		(legacy_teardrops no)
	)
	(paper "A4")
	(title_block
		(title "timecard-production-celestica-r4006 — R4006-B0001-02_R01.brd")
		(comment 1 "Time Appliance Project (Time Card) / footprints 81-84 of 1113")
	)
	(layers
		(0 "F.Cu" signal "TOP")
		(4 "In1.Cu" signal "L02_GND1")
		(6 "In2.Cu" signal "L03_SIG1")
		(8 "In3.Cu" signal "L04_GND2")
		(10 "In4.Cu" signal "L05_VCC1")
		(12 "In5.Cu" signal "L06_VCC2")
		(14 "In6.Cu" signal "L07_GND3")
		(16 "In7.Cu" signal "L08_SIG2")
		(18 "In8.Cu" signal "L09_GND4")
		(2 "B.Cu" signal "BOTTOM")
		(9 "F.Adhes" user "F.Adhesive")
		(11 "B.Adhes" user "B.Adhesive")
		(13 "F.Paste" user "Package Geometry/Pastemask Top")
		(15 "B.Paste" user "Package Geometry/Pastemask Bottom")
		(5 "F.SilkS" user "Ref Des/Silkscreen Top")
		(7 "B.SilkS" user "Ref Des/Silkscreen Bottom")
		(1 "F.Mask" user "Board Geometry/Soldermask Top")
		(3 "B.Mask" user "Board Geometry/Soldermask Bottom")
		(17 "Dwgs.User" user "User.Drawings")
		(19 "Cmts.User" user "User.Comments")
		(21 "Eco1.User" user "User.Eco1")
		(23 "Eco2.User" user "User.Eco2")
		(25 "Edge.Cuts" user "Board Geometry/Outline")
		(27 "Margin" user)
		(31 "F.CrtYd" user "Package Geometry/Place Bound Top")
		(29 "B.CrtYd" user "Package Geometry/Place Bound Bottom")
		(35 "F.Fab" user "Ref Des/Assembly Top")
		(33 "B.Fab" user "Ref Des/Assembly Bottom")
	)
	(footprint ""
		(layer "F.Cu")
		(at 90.2716 -44.868846 90)
		(property "Reference" "R266"
			(at -0.164846 -1.47193 90)
			(unlocked yes)
			(layer "F.SilkS")
			(effects
				(font
					(size 0.7874 0.5842)
					(thickness 0.1524)
				)
			)
		)
		(property "Value" "VAL*"
			(at 0.02032 2.13233 90)
			(unlocked yes)
			(layer "F.Fab")
			(hide yes)
			(effects
				(font
					(size 0.7874 0.5842)
					(thickness 0.1524)
				)
			)
		)
		(property "Device Type" "RESISTOR-G155-133R0-01,33OHM,1%"
			(at 0.008382 1.210564 90)
			(unlocked yes)
			(layer "F.Fab")
			(hide yes)
			(effects
				(font
					(size 0.7874 0.5842)
					(thickness 0.1524)
				)
			)
		)
		(property "User Part Number" "PARTNUM*"
			(at 0.02032 4.024884 90)
			(unlocked yes)
			(layer "Cmts.User")
			(hide yes)
			(effects
				(font
					(size 0.7874 0.5842)
					(thickness 0.1524)
				)
			)
		)
		(property "Tolerance" "TOL*"
			(at 0.044704 3.05435 90)
			(unlocked yes)
			(layer "Cmts.User")
			(hide yes)
			(effects
				(font
					(size 0.7874 0.5842)
					(thickness 0.1524)
				)
			)
		)
		(duplicate_pad_numbers_are_jumpers no)
		(fp_line
			(start 1.143 -0.5588)
			(end -1.143 -0.5588)
			(stroke
				(width 0.1)
				(type default)
			)
			(layer "F.SilkS")
		)
		(fp_line
			(start -1.143 -0.5588)
			(end -1.143 0.5588)
			(stroke
				(width 0.1)
				(type default)
			)
			(layer "F.SilkS")
		)
		(fp_line
			(start 1.143 0.5588)
			(end 1.143 -0.5588)
			(stroke
				(width 0.1)
				(type default)
			)
			(layer "F.SilkS")
		)
		(fp_line
			(start -1.143 0.5588)
			(end 1.143 0.5588)
			(stroke
				(width 0.1)
				(type default)
			)
			(layer "F.SilkS")
		)
		(fp_rect
			(start -1.143 -0.5588)
			(end 1.143 0.5588)
			(stroke
				(width 0)
				(type default)
			)
			(fill no)
			(layer "F.CrtYd")
		)
		(fp_line
			(start 0.508 -0.3048)
			(end -0.508 -0.3048)
			(stroke
				(width 0.1)
				(type default)
			)
			(layer "F.Fab")
		)
		(fp_line
			(start -0.508 -0.3048)
			(end -0.508 0.3048)
			(stroke
				(width 0.1)
				(type default)
			)
			(layer "F.Fab")
		)
		(fp_line
			(start 0.508 0.3048)
			(end 0.508 -0.3048)
			(stroke
				(width 0.1)
				(type default)
			)
			(layer "F.Fab")
		)
		(fp_line
			(start -0.508 0.3048)
			(end 0.508 0.3048)
			(stroke
				(width 0.1)
				(type default)
			)
			(layer "F.Fab")
		)
		(pad "1" smd rect
			(at -0.5334 0 90)
			(size 0.7112 0.6096)
			(layers "F.Cu" "F.Mask" "F.Paste")
			(net "RSVD_DBG_USB_MUX_SEL")
		)
		(pad "2" smd rect
			(at 0.5334 0 90)
			(size 0.7112 0.6096)
			(layers "F.Cu" "F.Mask" "F.Paste")
			(net "XP5R0V_USB_CONN_DET")
		)
		(zone
			(layer "F.Cu")
			(hatch none 0.5)
			(connect_pads
				(clearance 0)
			)
			(min_thickness 0.25)
			(keepout
				(tracks allowed)
				(vias not_allowed)
				(pads allowed)
				(copperpour not_allowed)
				(footprints allowed)
			)
			(placement
				(enabled no)
				(sheetname "")
			)
			(fill
				(thermal_gap 0.5)
				(thermal_bridge_width 0.5)
				(island_removal_mode 0)
			)
			(polygon
				(pts
					(xy 89.9668 -44.792646) (xy 90.5764 -44.792646) (xy 90.5764 -44.945046) (xy 89.9668 -44.945046)
				)
			)
		)
	)
	(footprint ""
		(layer "F.Cu")
		(at 47.244 -126.746)
		(property "Reference" "SP67"
			(at 0 0 0)
			(layer "F.SilkS")
			(hide yes)
			(effects
				(font
					(size 1.27 1.27)
				)
			)
		)
		(property "Value" ""
			(at 0 0 0)
			(layer "F.Fab")
			(effects
				(font
					(size 1.27 1.27)
				)
			)
		)
		(duplicate_pad_numbers_are_jumpers no)
	)
	(footprint ""
		(layer "F.Cu")
		(at 122.7074 -69.2912)
		(property "Reference" "TP40"
			(at -2.0066 -1.53543 0)
			(unlocked yes)
			(layer "F.SilkS")
			(effects
				(font
					(size 0.7874 0.5842)
					(thickness 0.1524)
				)
				(justify left)
			)
		)
		(property "Value" ""
			(at 0 0 0)
			(layer "F.Fab")
			(effects
				(font
					(size 1.27 1.27)
				)
			)
		)
		(property "Device Type" "TP_PIONT-TP010CT020B030_PTH-TPA"
			(at -1.341882 0.996696 0)
			(unlocked yes)
			(layer "F.Fab")
			(hide yes)
			(effects
				(font
					(size 0.7874 0.5842)
					(thickness 0.000001)
				)
				(justify left)
			)
		)
		(duplicate_pad_numbers_are_jumpers no)
		(fp_poly
			(pts
				(arc
					(start 0.889 0)
					(mid -0.889 0)
					(end 0.889 0)
				)
			)
			(stroke
				(width 0)
				(type default)
			)
			(fill no)
			(layer "B.CrtYd")
		)
		(fp_poly
			(pts
				(arc
					(start 0.889 0)
					(mid -0.889 0)
					(end 0.889 0)
				)
			)
			(stroke
				(width 0)
				(type default)
			)
			(fill no)
			(layer "F.CrtYd")
		)
		(pad "1" thru_hole circle
			(at 0 0)
			(size 0.508 0.508)
			(drill 0.254)
			(layers "*.Cu" "*.Mask")
			(remove_unused_layers no)
			(net "XP1R2V_FPGA_PG")
			(clearance 0.1016)
			(padstack
				(mode front_inner_back)
				(layer "Inner"
					(shape circle)
					(size 0.508 0.508)
					(clearance 0.1016)
				)
				(layer "B.Cu"
					(shape circle)
					(size 0.762 0.762)
					(clearance -0.0254)
				)
			)
		)
	)
	(footprint ""
		(layer "F.Cu")
		(at 135.001 -70.866 90)
		(property "Reference" "R182"
			(at 4.191 0.92837 90)
			(unlocked yes)
			(layer "F.SilkS")
			(effects
				(font
					(size 0.7874 0.5842)
					(thickness 0.1524)
				)
			)
		)
		(property "Value" "VAL*"
			(at 0.02032 2.13233 90)
			(unlocked yes)
			(layer "F.Fab")
			(hide yes)
			(effects
				(font
					(size 0.7874 0.5842)
					(thickness 0.1524)
				)
			)
		)
		(property "Device Type" "RESISTOR-G155-100R0-J0,0OHM,-"
			(at 0.008382 1.210564 90)
			(unlocked yes)
			(layer "F.Fab")
			(hide yes)
			(effects
				(font
					(size 0.7874 0.5842)
					(thickness 0.1524)
				)
			)
		)
		(property "User Part Number" "PARTNUM*"
			(at 0.02032 4.024884 90)
			(unlocked yes)
			(layer "Cmts.User")
			(hide yes)
			(effects
				(font
					(size 0.7874 0.5842)
					(thickness 0.1524)
				)
			)
		)
		(property "Tolerance" "TOL*"
			(at 0.044704 3.05435 90)
			(unlocked yes)
			(layer "Cmts.User")
			(hide yes)
			(effects
				(font
					(size 0.7874 0.5842)
					(thickness 0.1524)
				)
			)
		)
		(duplicate_pad_numbers_are_jumpers no)
		(fp_line
			(start 1.143 -0.5588)
			(end -1.143 -0.5588)
			(stroke
				(width 0.1)
				(type default)
			)
			(layer "F.SilkS")
		)
		(fp_line
			(start -1.143 -0.5588)
			(end -1.143 0.5588)
			(stroke
				(width 0.1)
				(type default)
			)
			(layer "F.SilkS")
		)
		(fp_line
			(start 1.143 0.5588)
			(end 1.143 -0.5588)
			(stroke
				(width 0.1)
				(type default)
			)
			(layer "F.SilkS")
		)
		(fp_line
			(start -1.143 0.5588)
			(end 1.143 0.5588)
			(stroke
				(width 0.1)
				(type default)
			)
			(layer "F.SilkS")
		)
		(fp_rect
			(start 1.143 0.5588)
			(end -1.143 -0.5588)
			(stroke
				(width 0)
				(type default)
			)
			(fill no)
			(layer "F.CrtYd")
		)
		(fp_line
			(start 0.508 -0.3048)
			(end -0.508 -0.3048)
			(stroke
				(width 0.1)
				(type default)
			)
			(layer "F.Fab")
		)
		(fp_line
			(start -0.508 -0.3048)
			(end -0.508 0.3048)
			(stroke
				(width 0.1)
				(type default)
			)
			(layer "F.Fab")
		)
		(fp_line
			(start 0.508 0.3048)
			(end 0.508 -0.3048)
			(stroke
				(width 0.1)
				(type default)
			)
			(layer "F.Fab")
		)
		(fp_line
			(start -0.508 0.3048)
			(end 0.508 0.3048)
			(stroke
				(width 0.1)
				(type default)
			)
			(layer "F.Fab")
		)
		(pad "1" smd rect
			(at -0.5334 0 90)
			(size 0.7112 0.6096)
			(layers "F.Cu" "F.Mask" "F.Paste")
			(net "XP1R8V_PG_R")
		)
		(pad "2" smd rect
			(at 0.5334 0 90)
			(size 0.7112 0.6096)
			(layers "F.Cu" "F.Mask" "F.Paste")
			(net "XP1R8V_FPGA_PG")
		)
		(zone
			(layer "F.Cu")
			(hatch none 0.5)
			(connect_pads
				(clearance 0)
			)
			(min_thickness 0.25)
			(keepout
				(tracks allowed)
				(vias not_allowed)
				(pads allowed)
				(copperpour not_allowed)
				(footprints allowed)
			)
			(placement
				(enabled no)
				(sheetname "")
			)
			(fill
				(thermal_gap 0.5)
				(thermal_bridge_width 0.5)
				(island_removal_mode 0)
			)
			(polygon
				(pts
					(xy 135.3058 -70.9422) (xy 134.6962 -70.9422) (xy 134.6962 -70.7898) (xy 135.3058 -70.7898)
				)
			)
		)
	)
)
